(kicad_pcb
	(version 20260206)
	(generator "pcbnew")
	(generator_version "10.0")
	(general
		(thickness 1.6)
		(legacy_teardrops no)
	)
	(paper "A4")
	(title_block
		(title "01162023_DA0F0TEBIF0_F0T_Expander_BD_F_brd_V02_OCP.brd")
		(comment 1 "Grand Teton / footprints 3075-3080 of 9728")
	)
	(layers
		(0 "F.Cu" signal "TOP")
		(4 "In1.Cu" signal "GND")
		(6 "In2.Cu" signal "VCC")
		(8 "In3.Cu" signal "VCC1")
		(10 "In4.Cu" signal "GND1")
		(12 "In5.Cu" signal "IN1")
		(14 "In6.Cu" signal "GND2")
		(16 "In7.Cu" signal "IN2")
		(18 "In8.Cu" signal "GND3")
		(20 "In9.Cu" signal "IN3")
		(22 "In10.Cu" signal "GND4")
		(24 "In11.Cu" signal "IN4")
		(26 "In12.Cu" signal "GND5")
		(28 "In13.Cu" signal "IN5")
		(30 "In14.Cu" signal "GND6")
		(32 "In15.Cu" signal "IN6")
		(34 "In16.Cu" signal "GND7")
		(2 "B.Cu" signal "BOTTOM")
		(9 "F.Adhes" user "F.Adhesive")
		(11 "B.Adhes" user "B.Adhesive")
		(13 "F.Paste" user "Package Geometry/Pastemask Top")
		(15 "B.Paste" user "Package Geometry/Pastemask Bottom")
		(5 "F.SilkS" user "Ref Des/Silkscreen Top")
		(7 "B.SilkS" user "Ref Des/Silkscreen Bottom")
		(1 "F.Mask" user "Board Geometry/Soldermask Top")
		(3 "B.Mask" user "Board Geometry/Soldermask Bottom")
		(17 "Dwgs.User" user "User.Drawings")
		(19 "Cmts.User" user "User.Comments")
		(21 "Eco1.User" user "User.Eco1")
		(23 "Eco2.User" user "User.Eco2")
		(25 "Edge.Cuts" user "Board Geometry/Outline")
		(27 "Margin" user)
		(31 "F.CrtYd" user "Package Geometry/Place Bound Top")
		(29 "B.CrtYd" user "Package Geometry/Place Bound Bottom")
		(35 "F.Fab" user "Ref Des/Assembly Top")
		(33 "B.Fab" user "Ref Des/Assembly Bottom")
	)
	(footprint ""
		(layer "F.Cu")
		(at 248.094754 -276.519386)
		(property "Reference" "R796"
			(at 0 0 0)
			(layer "F.SilkS")
			(hide yes)
			(effects
				(font
					(size 1.27 1.27)
				)
			)
		)
		(property "Value" ""
			(at 0 0 0)
			(layer "F.Fab")
			(effects
				(font
					(size 1.27 1.27)
				)
			)
		)
		(duplicate_pad_numbers_are_jumpers no)
		(fp_line
			(start -0.7874 -0.4064)
			(end 0.7874 -0.4064)
			(stroke
				(width 0.1524)
				(type default)
			)
			(layer "F.SilkS")
		)
		(fp_line
			(start -0.7874 0.4064)
			(end -0.7874 -0.4064)
			(stroke
				(width 0.1524)
				(type default)
			)
			(layer "F.SilkS")
		)
		(fp_line
			(start 0.7874 -0.4064)
			(end 0.7874 0.4064)
			(stroke
				(width 0.1524)
				(type default)
			)
			(layer "F.SilkS")
		)
		(fp_line
			(start 0.7874 0.4064)
			(end -0.7874 0.4064)
			(stroke
				(width 0.1524)
				(type default)
			)
			(layer "F.SilkS")
		)
		(fp_line
			(start -0.67945 -0.305054)
			(end -0.12065 -0.305054)
			(stroke
				(width 0.1)
				(type default)
			)
			(layer "F.Fab")
		)
		(fp_line
			(start -0.67945 0.3048)
			(end -0.67945 -0.305054)
			(stroke
				(width 0.1)
				(type default)
			)
			(layer "F.Fab")
		)
		(fp_line
			(start -0.12065 -0.305054)
			(end -0.12065 -0.2794)
			(stroke
				(width 0.1)
				(type default)
			)
			(layer "F.Fab")
		)
		(fp_line
			(start -0.12065 -0.2794)
			(end 0.12065 -0.2794)
			(stroke
				(width 0.1)
				(type default)
			)
			(layer "F.Fab")
		)
		(fp_line
			(start -0.12065 0.2794)
			(end -0.12065 0.3048)
			(stroke
				(width 0.1)
				(type default)
			)
			(layer "F.Fab")
		)
		(fp_line
			(start -0.12065 0.3048)
			(end -0.67945 0.3048)
			(stroke
				(width 0.1)
				(type default)
			)
			(layer "F.Fab")
		)
		(fp_line
			(start 0.120396 0.2794)
			(end -0.12065 0.2794)
			(stroke
				(width 0.1)
				(type default)
			)
			(layer "F.Fab")
		)
		(fp_line
			(start 0.120396 0.3048)
			(end 0.120396 0.2794)
			(stroke
				(width 0.1)
				(type default)
			)
			(layer "F.Fab")
		)
		(fp_line
			(start 0.12065 -0.3048)
			(end 0.67945 -0.3048)
			(stroke
				(width 0.1)
				(type default)
			)
			(layer "F.Fab")
		)
		(fp_line
			(start 0.12065 -0.2794)
			(end 0.12065 -0.3048)
			(stroke
				(width 0.1)
				(type default)
			)
			(layer "F.Fab")
		)
		(fp_line
			(start 0.67945 -0.3048)
			(end 0.67945 0.3048)
			(stroke
				(width 0.1)
				(type default)
			)
			(layer "F.Fab")
		)
		(fp_line
			(start 0.67945 0.3048)
			(end 0.120396 0.3048)
			(stroke
				(width 0.1)
				(type default)
			)
			(layer "F.Fab")
		)
		(pad "1" smd circle
			(at -0.40005 0)
			(size 0 0)
			(layers "F.Cu" "F.Mask" "F.Paste")
			(net "PEX2_P1V25_ADC_A0")
		)
		(pad "2" smd circle
			(at 0.40005 0)
			(size 0 0)
			(layers "F.Cu" "F.Mask" "F.Paste")
			(net "GND")
		)
	)
	(footprint ""
		(layer "F.Cu")
		(at 205.31455 -311.227978 135)
		(property "Reference" "R1307"
			(at 0 0 135)
			(layer "F.SilkS")
			(hide yes)
			(effects
				(font
					(size 1.27 1.27)
				)
			)
		)
		(property "Value" ""
			(at 0 0 135)
			(layer "F.Fab")
			(effects
				(font
					(size 1.27 1.27)
				)
			)
		)
		(duplicate_pad_numbers_are_jumpers no)
		(fp_line
			(start 0.787389 -0.406267)
			(end 0.787389 0.406267)
			(stroke
				(width 0.1524)
				(type default)
			)
			(layer "F.SilkS")
		)
		(fp_line
			(start 0.787389 0.406267)
			(end -0.787389 0.406267)
			(stroke
				(width 0.1524)
				(type default)
			)
			(layer "F.SilkS")
		)
		(fp_line
			(start -0.787389 -0.406267)
			(end 0.787389 -0.406267)
			(stroke
				(width 0.1524)
				(type default)
			)
			(layer "F.SilkS")
		)
		(fp_line
			(start -0.787389 0.406267)
			(end -0.787389 -0.406267)
			(stroke
				(width 0.1524)
				(type default)
			)
			(layer "F.SilkS")
		)
		(fp_line
			(start 0.679446 -0.30479)
			(end 0.679446 0.30479)
			(stroke
				(width 0.1)
				(type default)
			)
			(layer "F.Fab")
		)
		(fp_line
			(start 0.120515 -0.30479)
			(end 0.679446 -0.30479)
			(stroke
				(width 0.1)
				(type default)
			)
			(layer "F.Fab")
		)
		(fp_line
			(start 0.120695 -0.279466)
			(end 0.120515 -0.30479)
			(stroke
				(width 0.1)
				(type default)
			)
			(layer "F.Fab")
		)
		(fp_line
			(start 0.679446 0.30479)
			(end 0.120515 0.30479)
			(stroke
				(width 0.1)
				(type default)
			)
			(layer "F.Fab")
		)
		(fp_line
			(start -0.120695 -0.304969)
			(end -0.120695 -0.279466)
			(stroke
				(width 0.1)
				(type default)
			)
			(layer "F.Fab")
		)
		(fp_line
			(start -0.120695 -0.279466)
			(end 0.120695 -0.279466)
			(stroke
				(width 0.1)
				(type default)
			)
			(layer "F.Fab")
		)
		(fp_line
			(start 0.120335 0.279466)
			(end -0.120695 0.279466)
			(stroke
				(width 0.1)
				(type default)
			)
			(layer "F.Fab")
		)
		(fp_line
			(start 0.120515 0.30479)
			(end 0.120335 0.279466)
			(stroke
				(width 0.1)
				(type default)
			)
			(layer "F.Fab")
		)
		(fp_line
			(start -0.679446 -0.305149)
			(end -0.120695 -0.304969)
			(stroke
				(width 0.1)
				(type default)
			)
			(layer "F.Fab")
		)
		(fp_line
			(start -0.120695 0.279466)
			(end -0.120515 0.30479)
			(stroke
				(width 0.1)
				(type default)
			)
			(layer "F.Fab")
		)
		(fp_line
			(start -0.120515 0.30479)
			(end -0.679446 0.30479)
			(stroke
				(width 0.1)
				(type default)
			)
			(layer "F.Fab")
		)
		(fp_line
			(start -0.679446 0.30479)
			(end -0.679446 -0.305149)
			(stroke
				(width 0.1)
				(type default)
			)
			(layer "F.Fab")
		)
		(pad "1" smd circle
			(at -0.40005 0 135)
			(size 0 0)
			(layers "F.Cu" "F.Mask" "F.Paste")
			(net "PEX1_SPARE0")
		)
		(pad "2" smd circle
			(at 0.40005 0 135)
			(size 0 0)
			(layers "F.Cu" "F.Mask" "F.Paste")
			(net "P1V8_PEX")
		)
	)
	(footprint ""
		(layer "F.Cu")
		(at 145.924016 -190.978536 90)
		(property "Reference" "R6674"
			(at 0 0 90)
			(layer "F.SilkS")
			(hide yes)
			(effects
				(font
					(size 1.27 1.27)
				)
			)
		)
		(property "Value" ""
			(at 0 0 90)
			(layer "F.Fab")
			(effects
				(font
					(size 1.27 1.27)
				)
			)
		)
		(duplicate_pad_numbers_are_jumpers no)
		(fp_line
			(start 0.7874 -0.4064)
			(end 0.7874 0.4064)
			(stroke
				(width 0.1524)
				(type default)
			)
			(layer "F.SilkS")
		)
		(fp_line
			(start -0.7874 -0.4064)
			(end 0.7874 -0.4064)
			(stroke
				(width 0.1524)
				(type default)
			)
			(layer "F.SilkS")
		)
		(fp_line
			(start 0.7874 0.4064)
			(end -0.7874 0.4064)
			(stroke
				(width 0.1524)
				(type default)
			)
			(layer "F.SilkS")
		)
		(fp_line
			(start -0.7874 0.4064)
			(end -0.7874 -0.4064)
			(stroke
				(width 0.1524)
				(type default)
			)
			(layer "F.SilkS")
		)
		(fp_line
			(start -0.12065 -0.305054)
			(end -0.12065 -0.2794)
			(stroke
				(width 0.1)
				(type default)
			)
			(layer "F.Fab")
		)
		(fp_line
			(start -0.67945 -0.305054)
			(end -0.12065 -0.305054)
			(stroke
				(width 0.1)
				(type default)
			)
			(layer "F.Fab")
		)
		(fp_line
			(start 0.67945 -0.3048)
			(end 0.67945 0.3048)
			(stroke
				(width 0.1)
				(type default)
			)
			(layer "F.Fab")
		)
		(fp_line
			(start 0.12065 -0.3048)
			(end 0.67945 -0.3048)
			(stroke
				(width 0.1)
				(type default)
			)
			(layer "F.Fab")
		)
		(fp_line
			(start 0.12065 -0.2794)
			(end 0.12065 -0.3048)
			(stroke
				(width 0.1)
				(type default)
			)
			(layer "F.Fab")
		)
		(fp_line
			(start -0.12065 -0.2794)
			(end 0.12065 -0.2794)
			(stroke
				(width 0.1)
				(type default)
			)
			(layer "F.Fab")
		)
		(fp_line
			(start 0.120396 0.2794)
			(end -0.12065 0.2794)
			(stroke
				(width 0.1)
				(type default)
			)
			(layer "F.Fab")
		)
		(fp_line
			(start -0.12065 0.2794)
			(end -0.12065 0.3048)
			(stroke
				(width 0.1)
				(type default)
			)
			(layer "F.Fab")
		)
		(fp_line
			(start 0.67945 0.3048)
			(end 0.120396 0.3048)
			(stroke
				(width 0.1)
				(type default)
			)
			(layer "F.Fab")
		)
		(fp_line
			(start 0.120396 0.3048)
			(end 0.120396 0.2794)
			(stroke
				(width 0.1)
				(type default)
			)
			(layer "F.Fab")
		)
		(fp_line
			(start -0.12065 0.3048)
			(end -0.67945 0.3048)
			(stroke
				(width 0.1)
				(type default)
			)
			(layer "F.Fab")
		)
		(fp_line
			(start -0.67945 0.3048)
			(end -0.67945 -0.305054)
			(stroke
				(width 0.1)
				(type default)
			)
			(layer "F.Fab")
		)
		(pad "1" smd circle
			(at -0.40005 0 90)
			(size 0 0)
			(layers "F.Cu" "F.Mask" "F.Paste")
			(net "NIC5_CLK_EN_BUF_R_N")
		)
		(pad "2" smd circle
			(at 0.40005 0 90)
			(size 0 0)
			(layers "F.Cu" "F.Mask" "F.Paste")
			(net "P3V3")
		)
	)
	(footprint ""
		(layer "F.Cu")
		(at 238.124746 -117.714268)
		(property "Reference" "PC633"
			(at 0 0 0)
			(layer "F.SilkS")
			(hide yes)
			(effects
				(font
					(size 1.27 1.27)
				)
			)
		)
		(property "Value" ""
			(at 0 0 0)
			(layer "F.Fab")
			(effects
				(font
					(size 1.27 1.27)
				)
			)
		)
		(duplicate_pad_numbers_are_jumpers no)
		(fp_line
			(start -0.7874 -0.4064)
			(end 0.7874 -0.4064)
			(stroke
				(width 0.1524)
				(type default)
			)
			(layer "F.SilkS")
		)
		(fp_line
			(start -0.7874 0.4064)
			(end -0.7874 -0.4064)
			(stroke
				(width 0.1524)
				(type default)
			)
			(layer "F.SilkS")
		)
		(fp_line
			(start 0.7874 -0.4064)
			(end 0.7874 0.4064)
			(stroke
				(width 0.1524)
				(type default)
			)
			(layer "F.SilkS")
		)
		(fp_line
			(start 0.7874 0.4064)
			(end -0.7874 0.4064)
			(stroke
				(width 0.1524)
				(type default)
			)
			(layer "F.SilkS")
		)
		(fp_line
			(start -0.67945 -0.305054)
			(end -0.12065 -0.305054)
			(stroke
				(width 0.1)
				(type default)
			)
			(layer "F.Fab")
		)
		(fp_line
			(start -0.67945 0.3048)
			(end -0.67945 -0.305054)
			(stroke
				(width 0.1)
				(type default)
			)
			(layer "F.Fab")
		)
		(fp_line
			(start -0.12065 -0.305054)
			(end -0.12065 -0.2794)
			(stroke
				(width 0.1)
				(type default)
			)
			(layer "F.Fab")
		)
		(fp_line
			(start -0.12065 -0.2794)
			(end 0.12065 -0.2794)
			(stroke
				(width 0.1)
				(type default)
			)
			(layer "F.Fab")
		)
		(fp_line
			(start -0.12065 0.2794)
			(end -0.12065 0.3048)
			(stroke
				(width 0.1)
				(type default)
			)
			(layer "F.Fab")
		)
		(fp_line
			(start -0.12065 0.3048)
			(end -0.67945 0.3048)
			(stroke
				(width 0.1)
				(type default)
			)
			(layer "F.Fab")
		)
		(fp_line
			(start 0.120396 0.2794)
			(end -0.12065 0.2794)
			(stroke
				(width 0.1)
				(type default)
			)
			(layer "F.Fab")
		)
		(fp_line
			(start 0.120396 0.3048)
			(end 0.120396 0.2794)
			(stroke
				(width 0.1)
				(type default)
			)
			(layer "F.Fab")
		)
		(fp_line
			(start 0.12065 -0.3048)
			(end 0.67945 -0.3048)
			(stroke
				(width 0.1)
				(type default)
			)
			(layer "F.Fab")
		)
		(fp_line
			(start 0.12065 -0.2794)
			(end 0.12065 -0.3048)
			(stroke
				(width 0.1)
				(type default)
			)
			(layer "F.Fab")
		)
		(fp_line
			(start 0.67945 -0.3048)
			(end 0.67945 0.3048)
			(stroke
				(width 0.1)
				(type default)
			)
			(layer "F.Fab")
		)
		(fp_line
			(start 0.67945 0.3048)
			(end 0.120396 0.3048)
			(stroke
				(width 0.1)
				(type default)
			)
			(layer "F.Fab")
		)
		(pad "1" smd circle
			(at -0.40005 0)
			(size 0 0)
			(layers "F.Cu" "F.Mask" "F.Paste")
			(net "P12V_NIC3_CO_SS")
		)
		(pad "2" smd circle
			(at 0.40005 0)
			(size 0 0)
			(layers "F.Cu" "F.Mask" "F.Paste")
			(net "GND")
		)
	)
	(footprint ""
		(layer "F.Cu")
		(at 448.516502 -100.178108 90)
		(property "Reference" "PC330"
			(at 0 0 90)
			(layer "F.SilkS")
			(hide yes)
			(effects
				(font
					(size 1.27 1.27)
				)
			)
		)
		(property "Value" ""
			(at 0 0 90)
			(layer "F.Fab")
			(effects
				(font
					(size 1.27 1.27)
				)
			)
		)
		(duplicate_pad_numbers_are_jumpers no)
		(fp_line
			(start 0.7874 -0.4064)
			(end 0.7874 0.4064)
			(stroke
				(width 0.1524)
				(type default)
			)
			(layer "F.SilkS")
		)
		(fp_line
			(start -0.7874 -0.4064)
			(end 0.7874 -0.4064)
			(stroke
				(width 0.1524)
				(type default)
			)
			(layer "F.SilkS")
		)
		(fp_line
			(start 0.7874 0.4064)
			(end -0.7874 0.4064)
			(stroke
				(width 0.1524)
				(type default)
			)
			(layer "F.SilkS")
		)
		(fp_line
			(start -0.7874 0.4064)
			(end -0.7874 -0.4064)
			(stroke
				(width 0.1524)
				(type default)
			)
			(layer "F.SilkS")
		)
		(fp_line
			(start -0.12065 -0.305054)
			(end -0.12065 -0.2794)
			(stroke
				(width 0.1)
				(type default)
			)
			(layer "F.Fab")
		)
		(fp_line
			(start -0.67945 -0.305054)
			(end -0.12065 -0.305054)
			(stroke
				(width 0.1)
				(type default)
			)
			(layer "F.Fab")
		)
		(fp_line
			(start 0.67945 -0.3048)
			(end 0.67945 0.3048)
			(stroke
				(width 0.1)
				(type default)
			)
			(layer "F.Fab")
		)
		(fp_line
			(start 0.12065 -0.3048)
			(end 0.67945 -0.3048)
			(stroke
				(width 0.1)
				(type default)
			)
			(layer "F.Fab")
		)
		(fp_line
			(start 0.12065 -0.2794)
			(end 0.12065 -0.3048)
			(stroke
				(width 0.1)
				(type default)
			)
			(layer "F.Fab")
		)
		(fp_line
			(start -0.12065 -0.2794)
			(end 0.12065 -0.2794)
			(stroke
				(width 0.1)
				(type default)
			)
			(layer "F.Fab")
		)
		(fp_line
			(start 0.120396 0.2794)
			(end -0.12065 0.2794)
			(stroke
				(width 0.1)
				(type default)
			)
			(layer "F.Fab")
		)
		(fp_line
			(start -0.12065 0.2794)
			(end -0.12065 0.3048)
			(stroke
				(width 0.1)
				(type default)
			)
			(layer "F.Fab")
		)
		(fp_line
			(start 0.67945 0.3048)
			(end 0.120396 0.3048)
			(stroke
				(width 0.1)
				(type default)
			)
			(layer "F.Fab")
		)
		(fp_line
			(start 0.120396 0.3048)
			(end 0.120396 0.2794)
			(stroke
				(width 0.1)
				(type default)
			)
			(layer "F.Fab")
		)
		(fp_line
			(start -0.12065 0.3048)
			(end -0.67945 0.3048)
			(stroke
				(width 0.1)
				(type default)
			)
			(layer "F.Fab")
		)
		(fp_line
			(start -0.67945 0.3048)
			(end -0.67945 -0.305054)
			(stroke
				(width 0.1)
				(type default)
			)
			(layer "F.Fab")
		)
		(pad "1" smd circle
			(at -0.40005 0 90)
			(size 0 0)
			(layers "F.Cu" "F.Mask" "F.Paste")
			(net "P12V_AUX")
		)
		(pad "2" smd circle
			(at 0.40005 0 90)
			(size 0 0)
			(layers "F.Cu" "F.Mask" "F.Paste")
			(net "GND")
		)
	)
	(footprint ""
		(layer "F.Cu")
		(at 331.192378 -241.848894 -90)
		(property "Reference" "U143"
			(at 0.142494 1.753108 90)
			(unlocked yes)
			(layer "F.SilkS")
			(effects
				(font
					(size 0.7874 0.5842)
					(thickness 0.1524)
				)
			)
		)
		(property "Value" ""
			(at 0 0 270)
			(layer "F.Fab")
			(effects
				(font
					(size 1.27 1.27)
				)
			)
		)
		(duplicate_pad_numbers_are_jumpers no)
		(fp_line
			(start -1.7272 1.1176)
			(end -1.7272 -1.1176)
			(stroke
				(width 0.1524)
				(type default)
			)
			(layer "F.SilkS")
		)
		(fp_line
			(start 1.7272 1.1176)
			(end -1.7272 1.1176)
			(stroke
				(width 0.1524)
				(type default)
			)
			(layer "F.SilkS")
		)
		(fp_line
			(start 0 -0.7366)
			(end -0.254 -1.1176)
			(stroke
				(width 0.1524)
				(type default)
			)
			(layer "F.SilkS")
		)
		(fp_line
			(start -0.254 -1.1176)
			(end -1.7272 -1.1176)
			(stroke
				(width 0.1524)
				(type default)
			)
			(layer "F.SilkS")
		)
		(fp_line
			(start 0.254 -1.1176)
			(end 0 -0.7366)
			(stroke
				(width 0.1524)
				(type default)
			)
			(layer "F.SilkS")
		)
		(fp_line
			(start 1.7272 -1.1176)
			(end 1.7272 1.1176)
			(stroke
				(width 0.1524)
				(type default)
			)
			(layer "F.SilkS")
		)
		(fp_line
			(start 1.7272 -1.1176)
			(end 0.254 -1.1176)
			(stroke
				(width 0.1524)
				(type default)
			)
			(layer "F.SilkS")
		)
		(fp_poly
			(pts
				(xy -1.9558 -0.649986) (xy -2.7178 -0.268986) (xy -2.7178 -1.030986)
			)
			(stroke
				(width 0)
				(type default)
			)
			(fill yes)
			(layer "F.SilkS")
		)
		(fp_line
			(start -1.5748 1.1176)
			(end 1.5748 1.1176)
			(stroke
				(width 0.1)
				(type default)
			)
			(layer "F.Fab")
		)
		(fp_line
			(start 1.5748 1.1176)
			(end 1.5748 -1.1176)
			(stroke
				(width 0.1)
				(type default)
			)
			(layer "F.Fab")
		)
		(fp_line
			(start -1.5748 -1.1176)
			(end -1.5748 1.1176)
			(stroke
				(width 0.1)
				(type default)
			)
			(layer "F.Fab")
		)
		(fp_line
			(start 1.5748 -1.1176)
			(end -1.5748 -1.1176)
			(stroke
				(width 0.1)
				(type default)
			)
			(layer "F.Fab")
		)
		(fp_poly
			(pts
				(xy -1.9558 -0.649986) (xy -2.7178 -0.268986) (xy -2.7178 -1.030986)
			)
			(stroke
				(width 0)
				(type default)
			)
			(fill yes)
			(layer "F.Fab")
		)
		(pad "1" smd rect
			(at -0.999998 -0.649986 180)
			(size 0.3556 1.1176)
			(layers "F.Cu" "F.Mask" "F.Paste")
			(net "RST_MB_PERST_0_N")
		)
		(pad "2" smd rect
			(at -0.999998 0 180)
			(size 0.3556 1.1176)
			(layers "F.Cu" "F.Mask" "F.Paste")
			(net "GND")
		)
		(pad "3" smd rect
			(at -0.999998 0.649986 180)
			(size 0.3556 1.1176)
			(layers "F.Cu" "F.Mask" "F.Paste")
			(net "RST_MB_PERST_1_N")
		)
		(pad "4" smd rect
			(at 0.999998 0.649986 180)
			(size 0.3556 1.1176)
			(layers "F.Cu" "F.Mask" "F.Paste")
			(net "RST_MB_PERST_1_ISO_N")
		)
		(pad "5" smd rect
			(at 0.999998 0 180)
			(size 0.3556 1.1176)
			(layers "F.Cu" "F.Mask" "F.Paste")
			(net "P3V3_AUX")
		)
		(pad "6" smd rect
			(at 0.999998 -0.649986 180)
			(size 0.3556 1.1176)
			(layers "F.Cu" "F.Mask" "F.Paste")
			(net "RST_MB_PERST_0_ISO_N")
		)
	)
)
